(kicad_pcb
	(version 20260206)
	(generator "pcbnew")
	(generator_version "10.0")
	(general
		(thickness 1.6)
		(legacy_teardrops no)
	)
	(paper "A4")
	(title_block
		(title "04192023_DAF0TMB3IC0_F0TG_MB_C_brd_V02_OCP.brd")
		(comment 1 "Grand Teton / footprints 1822-1827 of 8354")
	)
	(layers
		(0 "F.Cu" signal "TOP")
		(4 "In1.Cu" signal "GND")
		(6 "In2.Cu" signal "IN1")
		(8 "In3.Cu" signal "GND1")
		(10 "In4.Cu" signal "IN2")
		(12 "In5.Cu" signal "GND2")
		(14 "In6.Cu" signal "IN3")
		(16 "In7.Cu" signal "GND3")
		(18 "In8.Cu" signal "VCC")
		(20 "In9.Cu" signal "VCC1")
		(22 "In10.Cu" signal "GND4")
		(24 "In11.Cu" signal "IN4")
		(26 "In12.Cu" signal "GND5")
		(28 "In13.Cu" signal "IN5")
		(30 "In14.Cu" signal "GND6")
		(32 "In15.Cu" signal "IN6")
		(34 "In16.Cu" signal "GND7")
		(2 "B.Cu" signal "BOTTOM")
		(9 "F.Adhes" user "F.Adhesive")
		(11 "B.Adhes" user "B.Adhesive")
		(13 "F.Paste" user "Package Geometry/Pastemask Top")
		(15 "B.Paste" user "Package Geometry/Pastemask Bottom")
		(5 "F.SilkS" user "Ref Des/Silkscreen Top")
		(7 "B.SilkS" user "Ref Des/Silkscreen Bottom")
		(1 "F.Mask" user "Board Geometry/Soldermask Top")
		(3 "B.Mask" user "Board Geometry/Soldermask Bottom")
		(17 "Dwgs.User" user "User.Drawings")
		(19 "Cmts.User" user "User.Comments")
		(21 "Eco1.User" user "User.Eco1")
		(23 "Eco2.User" user "User.Eco2")
		(25 "Edge.Cuts" user "Board Geometry/Outline")
		(27 "Margin" user)
		(31 "F.CrtYd" user "Package Geometry/Place Bound Top")
		(29 "B.CrtYd" user "Package Geometry/Place Bound Bottom")
		(35 "F.Fab" user "Ref Des/Assembly Top")
		(33 "B.Fab" user "Ref Des/Assembly Bottom")
	)
	(footprint ""
		(layer "F.Cu")
		(at 335.411064 -349.43161 180)
		(property "Reference" "PC104"
			(at 0.115316 -2.938272 0)
			(unlocked yes)
			(layer "F.SilkS")
			(effects
				(font
					(size 0.7874 0.5842)
					(thickness 0.1524)
				)
				(justify left)
			)
		)
		(property "Value" ""
			(at 0 0 180)
			(layer "F.Fab")
			(effects
				(font
					(size 1.27 1.27)
				)
			)
		)
		(duplicate_pad_numbers_are_jumpers no)
		(fp_line
			(start -3.400044 1.249934)
			(end 3.400044 1.249934)
			(stroke
				(width 0.1524)
				(type default)
			)
			(layer "F.SilkS")
		)
		(fp_circle
			(center 0 1.249934)
			(end -3.400044 1.249934)
			(stroke
				(width 0.1524)
				(type default)
			)
			(fill no)
			(layer "F.SilkS")
		)
		(fp_poly
			(pts
				(arc
					(start 3.400044 1.249934)
					(mid 0 4.649978)
					(end -3.400044 1.249934)
				)
			)
			(stroke
				(width 0)
				(type default)
			)
			(fill yes)
			(layer "F.SilkS")
		)
		(fp_circle
			(center 0 1.249934)
			(end -3.400044 1.249934)
			(stroke
				(width 0.1)
				(type default)
			)
			(fill no)
			(layer "F.Fab")
		)
		(pad "1" thru_hole rect
			(at 0 0 180)
			(size 1.524 1.524)
			(drill 1.016)
			(layers "*.Cu" "*.Mask")
			(remove_unused_layers no)
			(net "SW_P12V_AUX_PVDDCR_CPU1_P0_FLT")
			(clearance 0)
			(padstack
				(mode front_inner_back)
				(layer "Inner"
					(shape circle)
					(size 1.524 1.524)
					(clearance 0)
				)
				(layer "B.Cu"
					(shape rect)
					(size 1.524 1.524)
					(clearance 0)
				)
			)
		)
		(pad "2" thru_hole circle
			(at 0 2.500122 180)
			(size 1.524 1.524)
			(drill 1.016)
			(layers "*.Cu" "*.Mask")
			(remove_unused_layers no)
			(net "GND")
			(clearance 0)
		)
	)
	(footprint ""
		(layer "F.Cu")
		(at 167.871902 -436.78221)
		(property "Reference" "Q102"
			(at 2.473706 1.534414 0)
			(unlocked yes)
			(layer "F.SilkS")
			(effects
				(font
					(size 0.7874 0.5842)
					(thickness 0.1524)
				)
				(justify left)
			)
		)
		(property "Value" ""
			(at 0 0 0)
			(layer "F.Fab")
			(effects
				(font
					(size 1.27 1.27)
				)
			)
		)
		(duplicate_pad_numbers_are_jumpers no)
		(fp_line
			(start -1.332738 -1.100074)
			(end -0.4826 -1.100074)
			(stroke
				(width 0.1524)
				(type default)
			)
			(layer "F.SilkS")
		)
		(fp_line
			(start -1.332738 1.100074)
			(end -1.332738 -1.100074)
			(stroke
				(width 0.1524)
				(type default)
			)
			(layer "F.SilkS")
		)
		(fp_line
			(start -0.4826 -1.100074)
			(end 0 -0.541274)
			(stroke
				(width 0.1524)
				(type default)
			)
			(layer "F.SilkS")
		)
		(fp_line
			(start 0 -0.541274)
			(end 0.4826 -1.100074)
			(stroke
				(width 0.1524)
				(type default)
			)
			(layer "F.SilkS")
		)
		(fp_line
			(start 0.4826 -1.100074)
			(end 1.332738 -1.100074)
			(stroke
				(width 0.1524)
				(type default)
			)
			(layer "F.SilkS")
		)
		(fp_line
			(start 1.332738 -1.100074)
			(end 1.332738 1.100074)
			(stroke
				(width 0.1524)
				(type default)
			)
			(layer "F.SilkS")
		)
		(fp_line
			(start 1.332738 1.100074)
			(end -1.332738 1.100074)
			(stroke
				(width 0.1524)
				(type default)
			)
			(layer "F.SilkS")
		)
		(fp_poly
			(pts
				(xy -1.429766 -1.020064) (xy -2.15773 -1.313688) (xy -1.631696 -1.778508)
			)
			(stroke
				(width 0)
				(type default)
			)
			(fill yes)
			(layer "F.SilkS")
		)
		(fp_line
			(start -0.674878 -1.100074)
			(end 0.674878 -1.100074)
			(stroke
				(width 0.1)
				(type default)
			)
			(layer "F.Fab")
		)
		(fp_line
			(start -0.674878 1.100074)
			(end -0.674878 -1.100074)
			(stroke
				(width 0.1)
				(type default)
			)
			(layer "F.Fab")
		)
		(fp_line
			(start 0.674878 -1.100074)
			(end 0.674878 1.100074)
			(stroke
				(width 0.1)
				(type default)
			)
			(layer "F.Fab")
		)
		(fp_line
			(start 0.674878 1.100074)
			(end -0.674878 1.100074)
			(stroke
				(width 0.1)
				(type default)
			)
			(layer "F.Fab")
		)
		(fp_poly
			(pts
				(xy -2.2352 -0.298958) (xy -2.2352 -1.001014) (xy -1.533144 -0.649986)
			)
			(stroke
				(width 0)
				(type default)
			)
			(fill yes)
			(layer "F.Fab")
		)
		(pad "1" smd rect
			(at -0.94996 -0.649986 90)
			(size 0.4318 0.508)
			(layers "F.Cu" "F.Mask" "F.Paste")
			(net "GND")
		)
		(pad "2" smd rect
			(at -0.94996 0 90)
			(size 0.4318 0.508)
			(layers "F.Cu" "F.Mask" "F.Paste")
			(net "GPU_BASE_HMC_READY")
		)
		(pad "3" smd rect
			(at -0.94996 0.649986 90)
			(size 0.4318 0.508)
			(layers "F.Cu" "F.Mask" "F.Paste")
			(net "GPU_BASE_HMC_READY_ISO")
		)
		(pad "4" smd rect
			(at 0.94996 0.649986 90)
			(size 0.4318 0.508)
			(layers "F.Cu" "F.Mask" "F.Paste")
			(net "GND")
		)
		(pad "5" smd rect
			(at 0.94996 0 90)
			(size 0.4318 0.508)
			(layers "F.Cu" "F.Mask" "F.Paste")
			(net "GPU_BASE_HMC_READY_N")
		)
		(pad "6" smd rect
			(at 0.94996 -0.649986 90)
			(size 0.4318 0.508)
			(layers "F.Cu" "F.Mask" "F.Paste")
			(net "GPU_BASE_HMC_READY_N")
		)
	)
	(footprint ""
		(layer "F.Cu")
		(at 326.662288 -393.47648 180)
		(property "Reference" "L26"
			(at 0 0 180)
			(layer "F.SilkS")
			(hide yes)
			(effects
				(font
					(size 1.27 1.27)
				)
			)
		)
		(property "Value" ""
			(at 0 0 180)
			(layer "F.Fab")
			(effects
				(font
					(size 1.27 1.27)
				)
			)
		)
		(duplicate_pad_numbers_are_jumpers no)
		(fp_line
			(start 0.762 0.381)
			(end -0.762 0.381)
			(stroke
				(width 0.1524)
				(type default)
			)
			(layer "F.SilkS")
		)
		(fp_line
			(start 0.762 -0.381)
			(end 0.762 0.381)
			(stroke
				(width 0.1524)
				(type default)
			)
			(layer "F.SilkS")
		)
		(fp_line
			(start -0.762 0.381)
			(end -0.762 -0.381)
			(stroke
				(width 0.1524)
				(type default)
			)
			(layer "F.SilkS")
		)
		(fp_line
			(start -0.762 -0.381)
			(end 0.762 -0.381)
			(stroke
				(width 0.1524)
				(type default)
			)
			(layer "F.SilkS")
		)
		(fp_line
			(start 0.680466 0.306324)
			(end 0.118364 0.306324)
			(stroke
				(width 0.1)
				(type default)
			)
			(layer "F.Fab")
		)
		(fp_line
			(start 0.680466 -0.306324)
			(end 0.680466 0.306324)
			(stroke
				(width 0.1)
				(type default)
			)
			(layer "F.Fab")
		)
		(fp_line
			(start 0.118872 -0.2794)
			(end 0.118872 -0.306324)
			(stroke
				(width 0.1)
				(type default)
			)
			(layer "F.Fab")
		)
		(fp_line
			(start 0.118872 -0.306324)
			(end 0.680466 -0.306324)
			(stroke
				(width 0.1)
				(type default)
			)
			(layer "F.Fab")
		)
		(fp_line
			(start 0.118364 0.306324)
			(end 0.118364 0.2794)
			(stroke
				(width 0.1)
				(type default)
			)
			(layer "F.Fab")
		)
		(fp_line
			(start 0.118364 0.2794)
			(end -0.119634 0.2794)
			(stroke
				(width 0.1)
				(type default)
			)
			(layer "F.Fab")
		)
		(fp_line
			(start -0.118364 -0.2794)
			(end 0.118872 -0.2794)
			(stroke
				(width 0.1)
				(type default)
			)
			(layer "F.Fab")
		)
		(fp_line
			(start -0.118364 -0.307086)
			(end -0.118364 -0.2794)
			(stroke
				(width 0.1)
				(type default)
			)
			(layer "F.Fab")
		)
		(fp_line
			(start -0.119634 0.30607)
			(end -0.681736 0.30607)
			(stroke
				(width 0.1)
				(type default)
			)
			(layer "F.Fab")
		)
		(fp_line
			(start -0.119634 0.2794)
			(end -0.119634 0.30607)
			(stroke
				(width 0.1)
				(type default)
			)
			(layer "F.Fab")
		)
		(fp_line
			(start -0.681736 0.30607)
			(end -0.681736 -0.307086)
			(stroke
				(width 0.1)
				(type default)
			)
			(layer "F.Fab")
		)
		(fp_line
			(start -0.681736 -0.307086)
			(end -0.118364 -0.307086)
			(stroke
				(width 0.1)
				(type default)
			)
			(layer "F.Fab")
		)
		(pad "1" smd rect
			(at -0.40005 0)
			(size 0.4572 0.508)
			(layers "F.Cu" "F.Mask" "F.Paste")
			(net "P1V8_CPU0_RT_1D")
		)
		(pad "2" smd rect
			(at 0.40005 0)
			(size 0.4572 0.508)
			(layers "F.Cu" "F.Mask" "F.Paste")
			(net "P1V8_CPU0_RT0_1A_1D")
		)
	)
	(footprint ""
		(layer "F.Cu")
		(at 304.419 -365.125)
		(property "Reference" "R8073"
			(at 0 0 0)
			(layer "F.SilkS")
			(hide yes)
			(effects
				(font
					(size 1.27 1.27)
				)
			)
		)
		(property "Value" ""
			(at 0 0 0)
			(layer "F.Fab")
			(effects
				(font
					(size 1.27 1.27)
				)
			)
		)
		(duplicate_pad_numbers_are_jumpers no)
		(fp_line
			(start -0.7874 -0.4064)
			(end 0.7874 -0.4064)
			(stroke
				(width 0.1524)
				(type default)
			)
			(layer "F.SilkS")
		)
		(fp_line
			(start -0.7874 0.4064)
			(end -0.7874 -0.4064)
			(stroke
				(width 0.1524)
				(type default)
			)
			(layer "F.SilkS")
		)
		(fp_line
			(start 0.7874 -0.4064)
			(end 0.7874 0.4064)
			(stroke
				(width 0.1524)
				(type default)
			)
			(layer "F.SilkS")
		)
		(fp_line
			(start 0.7874 0.4064)
			(end -0.7874 0.4064)
			(stroke
				(width 0.1524)
				(type default)
			)
			(layer "F.SilkS")
		)
		(fp_line
			(start -0.67945 -0.305054)
			(end -0.12065 -0.305054)
			(stroke
				(width 0.1)
				(type default)
			)
			(layer "F.Fab")
		)
		(fp_line
			(start -0.67945 0.3048)
			(end -0.67945 -0.305054)
			(stroke
				(width 0.1)
				(type default)
			)
			(layer "F.Fab")
		)
		(fp_line
			(start -0.12065 -0.305054)
			(end -0.12065 -0.2794)
			(stroke
				(width 0.1)
				(type default)
			)
			(layer "F.Fab")
		)
		(fp_line
			(start -0.12065 -0.2794)
			(end 0.12065 -0.2794)
			(stroke
				(width 0.1)
				(type default)
			)
			(layer "F.Fab")
		)
		(fp_line
			(start -0.12065 0.2794)
			(end -0.12065 0.3048)
			(stroke
				(width 0.1)
				(type default)
			)
			(layer "F.Fab")
		)
		(fp_line
			(start -0.12065 0.3048)
			(end -0.67945 0.3048)
			(stroke
				(width 0.1)
				(type default)
			)
			(layer "F.Fab")
		)
		(fp_line
			(start 0.120396 0.2794)
			(end -0.12065 0.2794)
			(stroke
				(width 0.1)
				(type default)
			)
			(layer "F.Fab")
		)
		(fp_line
			(start 0.120396 0.3048)
			(end 0.120396 0.2794)
			(stroke
				(width 0.1)
				(type default)
			)
			(layer "F.Fab")
		)
		(fp_line
			(start 0.12065 -0.3048)
			(end 0.67945 -0.3048)
			(stroke
				(width 0.1)
				(type default)
			)
			(layer "F.Fab")
		)
		(fp_line
			(start 0.12065 -0.2794)
			(end 0.12065 -0.3048)
			(stroke
				(width 0.1)
				(type default)
			)
			(layer "F.Fab")
		)
		(fp_line
			(start 0.67945 -0.3048)
			(end 0.67945 0.3048)
			(stroke
				(width 0.1)
				(type default)
			)
			(layer "F.Fab")
		)
		(fp_line
			(start 0.67945 0.3048)
			(end 0.120396 0.3048)
			(stroke
				(width 0.1)
				(type default)
			)
			(layer "F.Fab")
		)
		(pad "1" smd circle
			(at -0.40005 0)
			(size 0 0)
			(layers "F.Cu" "F.Mask" "F.Paste")
			(net "PVDDCR_CPU1_P0_SMB_ALERT")
		)
		(pad "2" smd circle
			(at 0.40005 0)
			(size 0 0)
			(layers "F.Cu" "F.Mask" "F.Paste")
			(net "PVDDCR_CPU1_P0_SMB_ALERT_R")
		)
	)
	(footprint ""
		(layer "F.Cu")
		(at 22.892258 -427.580298 -90)
		(property "Reference" "R6165"
			(at 0 0 270)
			(layer "F.SilkS")
			(hide yes)
			(effects
				(font
					(size 1.27 1.27)
				)
			)
		)
		(property "Value" ""
			(at 0 0 270)
			(layer "F.Fab")
			(effects
				(font
					(size 1.27 1.27)
				)
			)
		)
		(duplicate_pad_numbers_are_jumpers no)
		(fp_line
			(start -0.7874 0.4064)
			(end -0.7874 -0.4064)
			(stroke
				(width 0.1524)
				(type default)
			)
			(layer "F.SilkS")
		)
		(fp_line
			(start 0.7874 0.4064)
			(end -0.7874 0.4064)
			(stroke
				(width 0.1524)
				(type default)
			)
			(layer "F.SilkS")
		)
		(fp_line
			(start -0.7874 -0.4064)
			(end 0.7874 -0.4064)
			(stroke
				(width 0.1524)
				(type default)
			)
			(layer "F.SilkS")
		)
		(fp_line
			(start 0.7874 -0.4064)
			(end 0.7874 0.4064)
			(stroke
				(width 0.1524)
				(type default)
			)
			(layer "F.SilkS")
		)
		(fp_line
			(start -0.67945 0.3048)
			(end -0.67945 -0.305054)
			(stroke
				(width 0.1)
				(type default)
			)
			(layer "F.Fab")
		)
		(fp_line
			(start -0.12065 0.3048)
			(end -0.67945 0.3048)
			(stroke
				(width 0.1)
				(type default)
			)
			(layer "F.Fab")
		)
		(fp_line
			(start 0.120396 0.3048)
			(end 0.120396 0.2794)
			(stroke
				(width 0.1)
				(type default)
			)
			(layer "F.Fab")
		)
		(fp_line
			(start 0.67945 0.3048)
			(end 0.120396 0.3048)
			(stroke
				(width 0.1)
				(type default)
			)
			(layer "F.Fab")
		)
		(fp_line
			(start -0.12065 0.2794)
			(end -0.12065 0.3048)
			(stroke
				(width 0.1)
				(type default)
			)
			(layer "F.Fab")
		)
		(fp_line
			(start 0.120396 0.2794)
			(end -0.12065 0.2794)
			(stroke
				(width 0.1)
				(type default)
			)
			(layer "F.Fab")
		)
		(fp_line
			(start -0.12065 -0.2794)
			(end 0.12065 -0.2794)
			(stroke
				(width 0.1)
				(type default)
			)
			(layer "F.Fab")
		)
		(fp_line
			(start 0.12065 -0.2794)
			(end 0.12065 -0.3048)
			(stroke
				(width 0.1)
				(type default)
			)
			(layer "F.Fab")
		)
		(fp_line
			(start 0.12065 -0.3048)
			(end 0.67945 -0.3048)
			(stroke
				(width 0.1)
				(type default)
			)
			(layer "F.Fab")
		)
		(fp_line
			(start 0.67945 -0.3048)
			(end 0.67945 0.3048)
			(stroke
				(width 0.1)
				(type default)
			)
			(layer "F.Fab")
		)
		(fp_line
			(start -0.67945 -0.305054)
			(end -0.12065 -0.305054)
			(stroke
				(width 0.1)
				(type default)
			)
			(layer "F.Fab")
		)
		(fp_line
			(start -0.12065 -0.305054)
			(end -0.12065 -0.2794)
			(stroke
				(width 0.1)
				(type default)
			)
			(layer "F.Fab")
		)
		(pad "1" smd circle
			(at -0.40005 0 270)
			(size 0 0)
			(layers "F.Cu" "F.Mask" "F.Paste")
			(net "P3V3_AUX")
		)
		(pad "2" smd circle
			(at 0.40005 0 270)
			(size 0 0)
			(layers "F.Cu" "F.Mask" "F.Paste")
			(net "FM_P2E_BUF2_EQB0")
		)
	)
	(footprint ""
		(layer "F.Cu")
		(at 263.906 -141.986 90)
		(property "Reference" "R1532"
			(at 0 0 90)
			(layer "F.SilkS")
			(hide yes)
			(effects
				(font
					(size 1.27 1.27)
				)
			)
		)
		(property "Value" ""
			(at 0 0 90)
			(layer "F.Fab")
			(effects
				(font
					(size 1.27 1.27)
				)
			)
		)
		(duplicate_pad_numbers_are_jumpers no)
		(fp_line
			(start 0.7874 -0.4064)
			(end 0.7874 0.4064)
			(stroke
				(width 0.1524)
				(type default)
			)
			(layer "F.SilkS")
		)
		(fp_line
			(start -0.7874 -0.4064)
			(end 0.7874 -0.4064)
			(stroke
				(width 0.1524)
				(type default)
			)
			(layer "F.SilkS")
		)
		(fp_line
			(start 0.7874 0.4064)
			(end -0.7874 0.4064)
			(stroke
				(width 0.1524)
				(type default)
			)
			(layer "F.SilkS")
		)
		(fp_line
			(start -0.7874 0.4064)
			(end -0.7874 -0.4064)
			(stroke
				(width 0.1524)
				(type default)
			)
			(layer "F.SilkS")
		)
		(fp_line
			(start -0.12065 -0.305054)
			(end -0.12065 -0.2794)
			(stroke
				(width 0.1)
				(type default)
			)
			(layer "F.Fab")
		)
		(fp_line
			(start -0.67945 -0.305054)
			(end -0.12065 -0.305054)
			(stroke
				(width 0.1)
				(type default)
			)
			(layer "F.Fab")
		)
		(fp_line
			(start 0.67945 -0.3048)
			(end 0.67945 0.3048)
			(stroke
				(width 0.1)
				(type default)
			)
			(layer "F.Fab")
		)
		(fp_line
			(start 0.12065 -0.3048)
			(end 0.67945 -0.3048)
			(stroke
				(width 0.1)
				(type default)
			)
			(layer "F.Fab")
		)
		(fp_line
			(start 0.12065 -0.2794)
			(end 0.12065 -0.3048)
			(stroke
				(width 0.1)
				(type default)
			)
			(layer "F.Fab")
		)
		(fp_line
			(start -0.12065 -0.2794)
			(end 0.12065 -0.2794)
			(stroke
				(width 0.1)
				(type default)
			)
			(layer "F.Fab")
		)
		(fp_line
			(start 0.120396 0.2794)
			(end -0.12065 0.2794)
			(stroke
				(width 0.1)
				(type default)
			)
			(layer "F.Fab")
		)
		(fp_line
			(start -0.12065 0.2794)
			(end -0.12065 0.3048)
			(stroke
				(width 0.1)
				(type default)
			)
			(layer "F.Fab")
		)
		(fp_line
			(start 0.67945 0.3048)
			(end 0.120396 0.3048)
			(stroke
				(width 0.1)
				(type default)
			)
			(layer "F.Fab")
		)
		(fp_line
			(start 0.120396 0.3048)
			(end 0.120396 0.2794)
			(stroke
				(width 0.1)
				(type default)
			)
			(layer "F.Fab")
		)
		(fp_line
			(start -0.12065 0.3048)
			(end -0.67945 0.3048)
			(stroke
				(width 0.1)
				(type default)
			)
			(layer "F.Fab")
		)
		(fp_line
			(start -0.67945 0.3048)
			(end -0.67945 -0.305054)
			(stroke
				(width 0.1)
				(type default)
			)
			(layer "F.Fab")
		)
		(pad "1" smd circle
			(at -0.40005 0 90)
			(size 0 0)
			(layers "F.Cu" "F.Mask" "F.Paste")
			(net "PVDD18_S5_P0")
		)
		(pad "2" smd circle
			(at 0.40005 0 90)
			(size 0 0)
			(layers "F.Cu" "F.Mask" "F.Paste")
			(net "SPI_CPU0_D0")
		)
	)
)
